(kicad_pcb
	(version 20260206)
	(generator "pcbnew")
	(generator_version "10.0")
	(general
		(thickness 1.6)
		(legacy_teardrops no)
	)
	(paper "A4")
	(title_block
		(title "v1-chassis-manager — T6M_CM_d_v01_1031_1645.brd")
		(comment 1 "Open CloudServer (Microsoft) / footprints 821-826 of 2512")
	)
	(layers
		(0 "F.Cu" signal "TOP")
		(4 "In1.Cu" signal "GND1")
		(6 "In2.Cu" signal "IN1")
		(8 "In3.Cu" signal "VCC1")
		(10 "In4.Cu" signal "VCC2")
		(12 "In5.Cu" signal "GND2")
		(14 "In6.Cu" signal "IN2")
		(16 "In7.Cu" signal "IN3")
		(18 "In8.Cu" signal "GND3")
		(2 "B.Cu" signal "BOTTOM")
		(9 "F.Adhes" user "F.Adhesive")
		(11 "B.Adhes" user "B.Adhesive")
		(13 "F.Paste" user "Package Geometry/Pastemask Top")
		(15 "B.Paste" user "Package Geometry/Pastemask Bottom")
		(5 "F.SilkS" user "Ref Des/Silkscreen Top")
		(7 "B.SilkS" user "Ref Des/Silkscreen Bottom")
		(1 "F.Mask" user "Board Geometry/Soldermask Top")
		(3 "B.Mask" user "Board Geometry/Soldermask Bottom")
		(17 "Dwgs.User" user "User.Drawings")
		(19 "Cmts.User" user "User.Comments")
		(21 "Eco1.User" user "User.Eco1")
		(23 "Eco2.User" user "User.Eco2")
		(25 "Edge.Cuts" user "Board Geometry/Outline")
		(27 "Margin" user)
		(31 "F.CrtYd" user "Package Geometry/Place Bound Top")
		(29 "B.CrtYd" user "Package Geometry/Place Bound Bottom")
		(35 "F.Fab" user "Ref Des/Assembly Top")
		(33 "B.Fab" user "Ref Des/Assembly Bottom")
	)
	(footprint ""
		(layer "F.Cu")
		(at 183.71185 -43.04157 90)
		(property "Reference" "J14"
			(at -8.561832 7.690358 0)
			(unlocked yes)
			(layer "F.SilkS")
			(effects
				(font
					(size 0.7874 0.5842)
					(thickness 0.1524)
				)
				(justify left)
			)
		)
		(property "Value" ""
			(at 0 0 90)
			(layer "F.Fab")
			(effects
				(font
					(size 1.27 1.27)
				)
			)
		)
		(duplicate_pad_numbers_are_jumpers no)
		(fp_line
			(start 4.953 -3.9878)
			(end -4.953 -3.9878)
			(stroke
				(width 0.1524)
				(type default)
			)
			(layer "F.SilkS")
		)
		(fp_line
			(start -7.62 -1.3716)
			(end -7.62 1.1176)
			(stroke
				(width 0.1524)
				(type default)
			)
			(layer "F.SilkS")
		)
		(fp_line
			(start 7.62 1.1176)
			(end 7.62 -1.3716)
			(stroke
				(width 0.1524)
				(type default)
			)
			(layer "F.SilkS")
		)
		(fp_line
			(start -7.62 4.318)
			(end -7.62 14.3764)
			(stroke
				(width 0.1524)
				(type default)
			)
			(layer "F.SilkS")
		)
		(fp_line
			(start 7.62 14.3764)
			(end 7.62 4.318)
			(stroke
				(width 0.1524)
				(type default)
			)
			(layer "F.SilkS")
		)
		(fp_line
			(start -7.62 14.3764)
			(end 7.62 14.3764)
			(stroke
				(width 0.1524)
				(type default)
			)
			(layer "F.SilkS")
		)
		(fp_poly
			(pts
				(xy -8.5725 0) (xy -10.4775 -0.762) (xy -10.4775 0.762)
			)
			(stroke
				(width 0)
				(type default)
			)
			(fill yes)
			(layer "F.SilkS")
		)
		(fp_poly
			(pts
				(xy -4.2926 -3.4036) (xy 4.2926 -3.4036) (xy 4.2926 -1.8288) (xy -4.2926 -1.8288)
			)
			(stroke
				(width 0)
				(type default)
			)
			(fill no)
			(layer "B.CrtYd")
		)
		(fp_poly
			(pts
				(xy 4.2926 -0.7874) (xy -4.2926 -0.7874) (xy -4.2926 0.7874) (xy 4.2926 0.7874)
			)
			(stroke
				(width 0)
				(type default)
			)
			(fill no)
			(layer "B.CrtYd")
		)
		(fp_poly
			(pts
				(arc
					(start 6.5659 -4.8006)
					(mid 5.272743 -4.264957)
					(end 4.7371 -2.9718)
				)
				(arc
					(start 4.7371 -2.9464)
					(mid 5.265304 -1.671204)
					(end 6.5405 -1.143)
				)
				(arc
					(start 6.5913 -1.143)
					(mid 8.4201 -2.9718)
					(end 6.5913 -4.8006)
				)
			)
			(stroke
				(width 0)
				(type default)
			)
			(fill no)
			(layer "B.CrtYd")
		)
		(fp_poly
			(pts
				(arc
					(start -6.5786 -4.8006)
					(mid -7.871757 -4.264957)
					(end -8.4074 -2.9718)
				)
				(arc
					(start -8.4074 -2.9464)
					(mid -7.879196 -1.671204)
					(end -6.604 -1.143)
				)
				(arc
					(start -6.5532 -1.143)
					(mid -4.7244 -2.9718)
					(end -6.5532 -4.8006)
				)
			)
			(stroke
				(width 0)
				(type default)
			)
			(fill no)
			(layer "B.CrtYd")
		)
		(fp_poly
			(pts
				(arc
					(start 6.5659 0.889)
					(mid 5.272743 1.424643)
					(end 4.7371 2.7178)
				)
				(arc
					(start 4.7371 2.7432)
					(mid 5.265304 4.018396)
					(end 6.5405 4.5466)
				)
				(arc
					(start 6.5913 4.5466)
					(mid 8.4201 2.7178)
					(end 6.5913 0.889)
				)
			)
			(stroke
				(width 0)
				(type default)
			)
			(fill no)
			(layer "B.CrtYd")
		)
		(fp_poly
			(pts
				(arc
					(start -6.5913 0.889)
					(mid -7.884457 1.424643)
					(end -8.4201 2.7178)
				)
				(arc
					(start -8.4201 2.7432)
					(mid -7.891896 4.018396)
					(end -6.6167 4.5466)
				)
				(arc
					(start -6.5659 4.5466)
					(mid -4.7371 2.7178)
					(end -6.5659 0.889)
				)
			)
			(stroke
				(width 0)
				(type default)
			)
			(fill no)
			(layer "B.CrtYd")
		)
		(fp_rect
			(start -8.7376 14.4526)
			(end 8.7376 -4.9276)
			(stroke
				(width 0)
				(type default)
			)
			(fill no)
			(layer "F.CrtYd")
		)
		(fp_line
			(start 7.62 -3.9878)
			(end 7.62 14.3764)
			(stroke
				(width 0.1)
				(type default)
			)
			(layer "F.Fab")
		)
		(fp_line
			(start -7.62 -3.9878)
			(end 7.62 -3.9878)
			(stroke
				(width 0.1)
				(type default)
			)
			(layer "F.Fab")
		)
		(fp_line
			(start -7.62 4.318)
			(end -7.62 -3.9878)
			(stroke
				(width 0.1)
				(type default)
			)
			(layer "F.Fab")
		)
		(fp_line
			(start 7.62 14.3764)
			(end -7.62 14.3764)
			(stroke
				(width 0.1)
				(type default)
			)
			(layer "F.Fab")
		)
		(fp_line
			(start -7.62 14.3764)
			(end -7.62 4.318)
			(stroke
				(width 0.1)
				(type default)
			)
			(layer "F.Fab")
		)
		(fp_poly
			(pts
				(xy -8.5725 0) (xy -10.4775 -0.762) (xy -10.4775 0.762)
			)
			(stroke
				(width 0)
				(type default)
			)
			(fill yes)
			(layer "F.Fab")
		)
		(fp_text user "5"
			(at -3.44932 -4.927854 0)
			(unlocked yes)
			(layer "F.SilkS")
			(effects
				(font
					(size 0.7874 0.5842)
					(thickness 0.1524)
				)
				(justify left)
			)
		)
		(fp_text user "8"
			(at 3.736594 -4.872736 0)
			(unlocked yes)
			(layer "F.SilkS")
			(effects
				(font
					(size 0.7874 0.5842)
					(thickness 0.1524)
				)
				(justify left)
			)
		)
		(fp_text user "1"
			(at -8.516366 -1.058418 0)
			(unlocked yes)
			(layer "F.SilkS")
			(effects
				(font
					(size 0.7874 0.5842)
					(thickness 0.1524)
				)
				(justify left)
			)
		)
		(fp_text user "4"
			(at 8.269478 -0.192532 0)
			(unlocked yes)
			(layer "F.SilkS")
			(effects
				(font
					(size 0.7874 0.5842)
					(thickness 0.1524)
				)
				(justify left)
			)
		)
		(fp_text user "8"
			(at 3.588258 -3.830574 0)
			(unlocked yes)
			(layer "B.SilkS")
			(effects
				(font
					(size 0.7874 0.5842)
					(thickness 0.1524)
				)
				(justify left mirror)
			)
		)
		(fp_text user "5"
			(at -3.569208 -3.71348 0)
			(unlocked yes)
			(layer "B.SilkS")
			(effects
				(font
					(size 0.7874 0.5842)
					(thickness 0.1524)
				)
				(justify left mirror)
			)
		)
		(fp_text user "1"
			(at -3.569208 1.502664 0)
			(unlocked yes)
			(layer "B.SilkS")
			(effects
				(font
					(size 0.7874 0.5842)
					(thickness 0.1524)
				)
				(justify left mirror)
			)
		)
		(fp_text user "4"
			(at 3.541268 1.759966 0)
			(unlocked yes)
			(layer "B.SilkS")
			(effects
				(font
					(size 0.7874 0.5842)
					(thickness 0.1524)
				)
				(justify left mirror)
			)
		)
		(fp_text user "8"
			(at 3.9624 -5.5372 90)
			(unlocked yes)
			(layer "B.Fab")
			(effects
				(font
					(size 1.016 0.762)
					(thickness 0.000001)
				)
				(justify left mirror)
			)
		)
		(fp_text user "5"
			(at -3.0734 -5.5372 90)
			(unlocked yes)
			(layer "B.Fab")
			(effects
				(font
					(size 1.016 0.762)
					(thickness 0.000001)
				)
				(justify left mirror)
			)
		)
		(fp_text user "4"
			(at 5.334 -0.118618 90)
			(unlocked yes)
			(layer "B.Fab")
			(effects
				(font
					(size 1.016 0.762)
					(thickness 0.000001)
				)
				(justify left mirror)
			)
		)
		(fp_text user "1"
			(at -4.572 -0.118618 90)
			(unlocked yes)
			(layer "B.Fab")
			(effects
				(font
					(size 1.016 0.762)
					(thickness 0.000001)
				)
				(justify left mirror)
			)
		)
		(fp_text user "8"
			(at 3.175 -5.5372 90)
			(unlocked yes)
			(layer "F.Fab")
			(effects
				(font
					(size 1.016 0.762)
					(thickness 0.000001)
				)
				(justify left)
			)
		)
		(fp_text user "5"
			(at -3.81 -5.5372 90)
			(unlocked yes)
			(layer "F.Fab")
			(effects
				(font
					(size 1.016 0.762)
					(thickness 0.000001)
				)
				(justify left)
			)
		)
		(fp_text user "4"
			(at 8.001 -0.118618 90)
			(unlocked yes)
			(layer "F.Fab")
			(effects
				(font
					(size 1.016 0.762)
					(thickness 0.000001)
				)
				(justify left)
			)
		)
		(fp_text user "1"
			(at -8.763 -0.118618 90)
			(unlocked yes)
			(layer "F.Fab")
			(effects
				(font
					(size 1.016 0.762)
					(thickness 0.000001)
				)
				(justify left)
			)
		)
		(pad "1" thru_hole rect
			(at -3.5052 0 90)
			(size 1.4732 1.4732)
			(drill 1.016)
			(layers "*.Cu" "*.Mask")
			(remove_unused_layers no)
			(net "USBPWR_P0")
			(clearance 0.0254)
			(thermal_gap 0.0254)
			(padstack
				(mode front_inner_back)
				(layer "Inner"
					(shape circle)
					(size 1.4732 1.4732)
					(clearance 0.0254)
				)
				(layer "B.Cu"
					(shape rect)
					(size 1.4732 1.4732)
					(clearance 0.0254)
				)
			)
		)
		(pad "2" thru_hole circle
			(at -1.016 0 90)
			(size 1.4732 1.4732)
			(drill 1.016)
			(layers "*.Cu" "*.Mask")
			(remove_unused_layers no)
			(net "USB0_L_DN")
			(clearance 0.0254)
			(thermal_gap 0.0254)
		)
		(pad "3" thru_hole circle
			(at 1.016 0 90)
			(size 1.4732 1.4732)
			(drill 1.016)
			(layers "*.Cu" "*.Mask")
			(remove_unused_layers no)
			(net "USB0_L_DP")
			(clearance 0.0254)
			(thermal_gap 0.0254)
		)
		(pad "4" thru_hole circle
			(at 3.5052 0 90)
			(size 1.4732 1.4732)
			(drill 1.016)
			(layers "*.Cu" "*.Mask")
			(remove_unused_layers no)
			(net "GND")
			(clearance 0.0254)
			(thermal_gap 0.0254)
		)
		(pad "5" thru_hole circle
			(at -3.5052 -2.6162 90)
			(size 1.4732 1.4732)
			(drill 1.016)
			(layers "*.Cu" "*.Mask")
			(remove_unused_layers no)
			(net "USBPWR_P0")
			(clearance 0.0254)
			(thermal_gap 0.0254)
		)
		(pad "6" thru_hole circle
			(at -1.016 -2.6162 90)
			(size 1.4732 1.4732)
			(drill 1.016)
			(layers "*.Cu" "*.Mask")
			(remove_unused_layers no)
			(net "USB1_L_DN")
			(clearance 0.0254)
			(thermal_gap 0.0254)
		)
		(pad "7" thru_hole circle
			(at 1.016 -2.6162 90)
			(size 1.4732 1.4732)
			(drill 1.016)
			(layers "*.Cu" "*.Mask")
			(remove_unused_layers no)
			(net "USB1_L_DP")
			(clearance 0.0254)
			(thermal_gap 0.0254)
		)
		(pad "8" thru_hole circle
			(at 3.5052 -2.6162 90)
			(size 1.4732 1.4732)
			(drill 1.016)
			(layers "*.Cu" "*.Mask")
			(remove_unused_layers no)
			(net "GND")
			(clearance 0.0254)
			(thermal_gap 0.0254)
		)
		(pad "9" thru_hole circle
			(at -6.5786 2.7178 90)
			(size 3.556 3.556)
			(drill 2.286)
			(layers "*.Cu" "*.Mask")
			(remove_unused_layers no)
			(net "GND")
			(clearance -0.381)
		)
		(pad "10" thru_hole circle
			(at 6.5786 2.7178 90)
			(size 3.556 3.556)
			(drill 2.286)
			(layers "*.Cu" "*.Mask")
			(remove_unused_layers no)
			(net "GND")
			(clearance -0.381)
		)
		(pad "11" thru_hole circle
			(at -6.5786 -2.9718 90)
			(size 3.556 3.556)
			(drill 2.286)
			(layers "*.Cu" "*.Mask")
			(remove_unused_layers no)
			(net "GND")
			(clearance -0.381)
		)
		(pad "12" thru_hole circle
			(at 6.5786 -2.9718 90)
			(size 3.556 3.556)
			(drill 2.286)
			(layers "*.Cu" "*.Mask")
			(remove_unused_layers no)
			(net "GND")
			(clearance -0.381)
		)
	)
	(footprint ""
		(layer "F.Cu")
		(at 123.682252 -162.464242)
		(property "Reference" "R1248"
			(at 29.77388 46.490636 0)
			(unlocked yes)
			(layer "F.SilkS")
			(effects
				(font
					(size 0.7874 0.5842)
					(thickness 0.1524)
				)
				(justify left)
			)
		)
		(property "Value" ""
			(at 0 0 0)
			(layer "F.Fab")
			(effects
				(font
					(size 1.27 1.27)
				)
			)
		)
		(duplicate_pad_numbers_are_jumpers no)
		(fp_line
			(start -0.7874 -0.4064)
			(end 0.7874 -0.4064)
			(stroke
				(width 0.1524)
				(type default)
			)
			(layer "F.SilkS")
		)
		(fp_line
			(start -0.7874 0.4064)
			(end -0.7874 -0.4064)
			(stroke
				(width 0.1524)
				(type default)
			)
			(layer "F.SilkS")
		)
		(fp_line
			(start 0.7874 -0.4064)
			(end 0.7874 0.4064)
			(stroke
				(width 0.1524)
				(type default)
			)
			(layer "F.SilkS")
		)
		(fp_line
			(start 0.7874 0.4064)
			(end -0.7874 0.4064)
			(stroke
				(width 0.1524)
				(type default)
			)
			(layer "F.SilkS")
		)
		(fp_poly
			(pts
				(xy -0.508 0.2794) (xy -0.508 0.2286) (xy -0.635 0.2286) (xy -0.635 -0.254) (xy -0.5334 -0.254)
				(xy -0.5334 -0.2794) (xy 0.5334 -0.2794) (xy 0.5334 -0.254) (xy 0.635 -0.254) (xy 0.635 0.254) (xy 0.5334 0.254)
				(xy 0.5334 0.2794)
			)
			(stroke
				(width 0)
				(type default)
			)
			(fill no)
			(layer "F.CrtYd")
		)
		(pad "1" smd rect
			(at 0.40005 0)
			(size 0.4572 0.508)
			(layers "F.Cu" "F.Mask" "F.Paste")
			(net "P3V3_NODE1")
		)
		(pad "2" smd rect
			(at -0.40005 0)
			(size 0.4572 0.508)
			(layers "F.Cu" "F.Mask" "F.Paste")
			(net "UART_CMC_RX_P")
		)
	)
	(footprint ""
		(layer "F.Cu")
		(at 167.558212 -174.366428 90)
		(property "Reference" "R1303"
			(at 1.076706 0.131572 90)
			(unlocked yes)
			(layer "F.SilkS")
			(effects
				(font
					(size 0.7874 0.5842)
					(thickness 0.1524)
				)
				(justify left)
			)
		)
		(property "Value" ""
			(at 0 0 90)
			(layer "F.Fab")
			(effects
				(font
					(size 1.27 1.27)
				)
			)
		)
		(duplicate_pad_numbers_are_jumpers no)
		(fp_line
			(start 0.7874 -0.4064)
			(end 0.7874 0.4064)
			(stroke
				(width 0.1524)
				(type default)
			)
			(layer "F.SilkS")
		)
		(fp_line
			(start -0.7874 -0.4064)
			(end 0.7874 -0.4064)
			(stroke
				(width 0.1524)
				(type default)
			)
			(layer "F.SilkS")
		)
		(fp_line
			(start 0.7874 0.4064)
			(end -0.7874 0.4064)
			(stroke
				(width 0.1524)
				(type default)
			)
			(layer "F.SilkS")
		)
		(fp_line
			(start -0.7874 0.4064)
			(end -0.7874 -0.4064)
			(stroke
				(width 0.1524)
				(type default)
			)
			(layer "F.SilkS")
		)
		(fp_poly
			(pts
				(xy -0.508 0.2794) (xy -0.508 0.2286) (xy -0.635 0.2286) (xy -0.635 -0.254) (xy -0.5334 -0.254)
				(xy -0.5334 -0.2794) (xy 0.5334 -0.2794) (xy 0.5334 -0.254) (xy 0.635 -0.254) (xy 0.635 0.254) (xy 0.5334 0.254)
				(xy 0.5334 0.2794)
			)
			(stroke
				(width 0)
				(type default)
			)
			(fill no)
			(layer "F.CrtYd")
		)
		(pad "1" smd rect
			(at 0.40005 0 90)
			(size 0.4572 0.508)
			(layers "F.Cu" "F.Mask" "F.Paste")
			(net "GND")
		)
		(pad "2" smd rect
			(at -0.40005 0 90)
			(size 0.4572 0.508)
			(layers "F.Cu" "F.Mask" "F.Paste")
			(net "N54365542")
		)
	)
	(footprint ""
		(layer "F.Cu")
		(at 41.638982 -9.1186 -90)
		(property "Reference" "PC77"
			(at -0.18034 10.21969 90)
			(unlocked yes)
			(layer "F.SilkS")
			(effects
				(font
					(size 0.7874 0.5842)
					(thickness 0.1524)
				)
				(justify left)
			)
		)
		(property "Value" ""
			(at 0 0 270)
			(layer "F.Fab")
			(effects
				(font
					(size 1.27 1.27)
				)
			)
		)
		(duplicate_pad_numbers_are_jumpers no)
		(fp_line
			(start -0.7874 0.4064)
			(end -0.7874 -0.4064)
			(stroke
				(width 0.1524)
				(type default)
			)
			(layer "F.SilkS")
		)
		(fp_line
			(start 0.7874 0.4064)
			(end -0.7874 0.4064)
			(stroke
				(width 0.1524)
				(type default)
			)
			(layer "F.SilkS")
		)
		(fp_line
			(start 0 0.381)
			(end 0 -0.381)
			(stroke
				(width 0.1524)
				(type default)
			)
			(layer "F.SilkS")
		)
		(fp_line
			(start -0.7874 -0.4064)
			(end 0.7874 -0.4064)
			(stroke
				(width 0.1524)
				(type default)
			)
			(layer "F.SilkS")
		)
		(fp_line
			(start 0.7874 -0.4064)
			(end 0.7874 0.4064)
			(stroke
				(width 0.1524)
				(type default)
			)
			(layer "F.SilkS")
		)
		(fp_poly
			(pts
				(xy -0.5334 0.254) (xy -0.635 0.254) (xy -0.635 0.2286) (xy -0.635 -0.254) (xy -0.5334 -0.254) (xy -0.5334 -0.2794)
				(xy 0.5334 -0.2794) (xy 0.5334 -0.254) (xy 0.635 -0.254) (xy 0.635 0.254) (xy 0.5334 0.254) (xy 0.5334 0.2794)
				(xy -0.508 0.2794) (xy -0.5334 0.2794)
			)
			(stroke
				(width 0)
				(type default)
			)
			(fill no)
			(layer "F.CrtYd")
		)
		(pad "1" smd rect
			(at 0.40005 0 270)
			(size 0.4572 0.508)
			(layers "F.Cu" "F.Mask" "F.Paste")
			(net "SW_PV_VDDR_NODE1_BT")
		)
		(pad "2" smd rect
			(at -0.40005 0 270)
			(size 0.4572 0.508)
			(layers "F.Cu" "F.Mask" "F.Paste")
			(net "SW_PV_VDDR_NODE1_PH")
		)
	)
	(footprint ""
		(layer "F.Cu")
		(at 12.587986 -11.613896 90)
		(property "Reference" "R215"
			(at -0.984758 -4.622038 90)
			(unlocked yes)
			(layer "F.SilkS")
			(effects
				(font
					(size 0.7874 0.5842)
					(thickness 0.1524)
				)
				(justify left)
			)
		)
		(property "Value" ""
			(at 0 0 90)
			(layer "F.Fab")
			(effects
				(font
					(size 1.27 1.27)
				)
			)
		)
		(duplicate_pad_numbers_are_jumpers no)
		(fp_line
			(start 0.7874 -0.4064)
			(end 0.7874 0.4064)
			(stroke
				(width 0.1524)
				(type default)
			)
			(layer "F.SilkS")
		)
		(fp_line
			(start -0.7874 -0.4064)
			(end 0.7874 -0.4064)
			(stroke
				(width 0.1524)
				(type default)
			)
			(layer "F.SilkS")
		)
		(fp_line
			(start 0.7874 0.4064)
			(end -0.7874 0.4064)
			(stroke
				(width 0.1524)
				(type default)
			)
			(layer "F.SilkS")
		)
		(fp_line
			(start -0.7874 0.4064)
			(end -0.7874 -0.4064)
			(stroke
				(width 0.1524)
				(type default)
			)
			(layer "F.SilkS")
		)
		(fp_poly
			(pts
				(xy -0.508 0.2794) (xy -0.508 0.2286) (xy -0.635 0.2286) (xy -0.635 -0.254) (xy -0.5334 -0.254)
				(xy -0.5334 -0.2794) (xy 0.5334 -0.2794) (xy 0.5334 -0.254) (xy 0.635 -0.254) (xy 0.635 0.254) (xy 0.5334 0.254)
				(xy 0.5334 0.2794)
			)
			(stroke
				(width 0)
				(type default)
			)
			(fill no)
			(layer "F.CrtYd")
		)
		(pad "1" smd rect
			(at 0.40005 0 90)
			(size 0.4572 0.508)
			(layers "F.Cu" "F.Mask" "F.Paste")
			(net "PV_VDDR_NODE1")
		)
		(pad "2" smd rect
			(at -0.40005 0 90)
			(size 0.4572 0.508)
			(layers "F.Cu" "F.Mask" "F.Paste")
			(net "PV_VDDR_NODE1_VREF_R")
		)
	)
	(footprint ""
		(layer "F.Cu")
		(at 149.057868 -39.972996 90)
		(property "Reference" "R1008"
			(at -1.681226 10.212832 90)
			(unlocked yes)
			(layer "F.SilkS")
			(effects
				(font
					(size 0.7874 0.5842)
					(thickness 0.1524)
				)
				(justify left)
			)
		)
		(property "Value" ""
			(at 0 0 90)
			(layer "F.Fab")
			(effects
				(font
					(size 1.27 1.27)
				)
			)
		)
		(duplicate_pad_numbers_are_jumpers no)
		(fp_line
			(start 0.7874 -0.4064)
			(end 0.7874 0.4064)
			(stroke
				(width 0.1524)
				(type default)
			)
			(layer "F.SilkS")
		)
		(fp_line
			(start -0.7874 -0.4064)
			(end 0.7874 -0.4064)
			(stroke
				(width 0.1524)
				(type default)
			)
			(layer "F.SilkS")
		)
		(fp_line
			(start 0.7874 0.4064)
			(end -0.7874 0.4064)
			(stroke
				(width 0.1524)
				(type default)
			)
			(layer "F.SilkS")
		)
		(fp_line
			(start -0.7874 0.4064)
			(end -0.7874 -0.4064)
			(stroke
				(width 0.1524)
				(type default)
			)
			(layer "F.SilkS")
		)
		(fp_poly
			(pts
				(xy -0.508 0.2794) (xy -0.508 0.2286) (xy -0.635 0.2286) (xy -0.635 -0.254) (xy -0.5334 -0.254)
				(xy -0.5334 -0.2794) (xy 0.5334 -0.2794) (xy 0.5334 -0.254) (xy 0.635 -0.254) (xy 0.635 0.254) (xy 0.5334 0.254)
				(xy 0.5334 0.2794)
			)
			(stroke
				(width 0)
				(type default)
			)
			(fill no)
			(layer "F.CrtYd")
		)
		(pad "1" smd rect
			(at 0.40005 0 90)
			(size 0.4572 0.508)
			(layers "F.Cu" "F.Mask" "F.Paste")
			(net "GND")
		)
		(pad "2" smd rect
			(at -0.40005 0 90)
			(size 0.4572 0.508)
			(layers "F.Cu" "F.Mask" "F.Paste")
			(net "UART_DTR_P1_N")
		)
	)
)
